(kicad_pcb
	(version 20241229)
	(generator "pcbnew")
	(generator_version "9.0")
	(general
		(thickness 1.711)
		(legacy_teardrops no)
	)
	(paper "A4")
	(title_block
		(title "Antmicro Baseboard for Jetson AGX Thor")
		(date "2026-02-18")
		(rev "1.1.0")
		(company "Antmicro Ltd")
		(comment 1 "www.antmicro.com")
		(comment 9 "footprints 1043-1046 of 1170")
	)
	(layers
		(0 "F.Cu" signal)
		(4 "In1.Cu" signal)
		(6 "In2.Cu" signal)
		(8 "In3.Cu" signal)
		(10 "In4.Cu" jumper)
		(12 "In5.Cu" signal)
		(14 "In6.Cu" signal)
		(16 "In7.Cu" signal)
		(18 "In8.Cu" signal)
		(2 "B.Cu" signal)
		(9 "F.Adhes" user "F.Adhesive")
		(11 "B.Adhes" user "B.Adhesive")
		(13 "F.Paste" user)
		(15 "B.Paste" user)
		(5 "F.SilkS" user "F.Silkscreen")
		(7 "B.SilkS" user "B.Silkscreen")
		(1 "F.Mask" user)
		(3 "B.Mask" user)
		(17 "Dwgs.User" user "User.Drawings")
		(19 "Cmts.User" user "User.Comments")
		(21 "Eco1.User" user "User.Eco1")
		(23 "Eco2.User" user "User.Eco2")
		(25 "Edge.Cuts" user)
		(27 "Margin" user)
		(31 "F.CrtYd" user "F.Courtyard")
		(29 "B.CrtYd" user "B.Courtyard")
		(35 "F.Fab" user)
		(33 "B.Fab" user)
	)
	(footprint "antmicro-footprints:C_0402_1005Metric"
		(layer "B.Cu")
		(at 94.180001 103.6 -90)
		(descr "Capacitor SMD 0402")
		(tags "capacitor SMD 0402")
		(property "Reference" "C330"
			(at -3.8 -0.3 90)
			(layer "B.SilkS")
			(effects
				(font
					(size 0.7 0.7)
					(thickness 0.15)
				)
				(justify left bottom mirror)
			)
		)
		(property "Value" "C_100n_0402"
			(at -1.022927 -2.155213 90)
			(layer "B.Fab")
			(effects
				(font
					(size 0.7 0.7)
					(thickness 0.15)
				)
				(justify left bottom mirror)
			)
		)
		(property "Datasheet" "https://www.murata.com/products/productdetail?partno=GRM155R61H104KE14%23"
			(at 0 0 90)
			(layer "B.Fab")
			(hide yes)
			(effects
				(font
					(size 1.27 1.27)
					(thickness 0.15)
				)
				(justify mirror)
			)
		)
		(property "Description" "SMD Multilayer Ceramic Capacitor, 0.1 µF, 50 V, 0402 [1005 Metric], ± 10%, X5R, GRM Series"
			(at 0 0 90)
			(layer "B.Fab")
			(hide yes)
			(effects
				(font
					(size 1.27 1.27)
					(thickness 0.15)
				)
				(justify mirror)
			)
		)
		(property "Manufacturer" "Murata"
			(at 0 0 90)
			(unlocked yes)
			(layer "B.Fab")
			(hide yes)
			(effects
				(font
					(size 1 1)
					(thickness 0.15)
				)
				(justify mirror)
			)
		)
		(property "MPN" "GRM155R61H104KE14D"
			(at 0 0 90)
			(unlocked yes)
			(layer "B.Fab")
			(hide yes)
			(effects
				(font
					(size 1 1)
					(thickness 0.15)
				)
				(justify mirror)
			)
		)
		(property "Val" "100n"
			(at 0 0 90)
			(unlocked yes)
			(layer "B.Fab")
			(hide yes)
			(effects
				(font
					(size 1 1)
					(thickness 0.15)
				)
				(justify mirror)
			)
		)
		(property "License" "Apache-2.0"
			(at 0 0 90)
			(unlocked yes)
			(layer "B.Fab")
			(hide yes)
			(effects
				(font
					(size 1 1)
					(thickness 0.15)
				)
				(justify mirror)
			)
		)
		(property "Author" "Antmicro"
			(at 0 0 90)
			(unlocked yes)
			(layer "B.Fab")
			(hide yes)
			(effects
				(font
					(size 1 1)
					(thickness 0.15)
				)
				(justify mirror)
			)
		)
		(property "Voltage" "50V"
			(at 0 0 90)
			(unlocked yes)
			(layer "B.Fab")
			(hide yes)
			(effects
				(font
					(size 1 1)
					(thickness 0.15)
				)
				(justify mirror)
			)
		)
		(property "Dielectric" "X5R"
			(at 0 0 90)
			(unlocked yes)
			(layer "B.Fab")
			(hide yes)
			(effects
				(font
					(size 1 1)
					(thickness 0.15)
				)
				(justify mirror)
			)
		)
		(sheetname "/SoM_IO2/")
		(sheetfile "som_io2.kicad_sch")
		(attr smd)
		(fp_poly
			(pts
				(xy -0.925 0.47) (xy 0.925 0.47) (xy 0.925 -0.47) (xy -0.925 -0.47)
			)
			(stroke
				(width 0.05)
				(type default)
			)
			(fill no)
			(layer "B.CrtYd")
		)
		(fp_line
			(start -0.494 0.25)
			(end 0.504 0.25)
			(stroke
				(width 0.15)
				(type solid)
			)
			(layer "B.Fab")
		)
		(fp_line
			(start 0.504 0.25)
			(end 0.504 -0.248)
			(stroke
				(width 0.15)
				(type solid)
			)
			(layer "B.Fab")
		)
		(fp_line
			(start -0.494 -0.248)
			(end -0.494 0.25)
			(stroke
				(width 0.15)
				(type solid)
			)
			(layer "B.Fab")
		)
		(fp_line
			(start 0.504 -0.248)
			(end -0.494 -0.248)
			(stroke
				(width 0.15)
				(type solid)
			)
			(layer "B.Fab")
		)
		(fp_text user "Author: Antmicro"
			(at -0.939 -3.399 90)
			(layer "B.Fab")
			(effects
				(font
					(size 0.7 0.7)
					(thickness 0.15)
				)
				(justify left bottom mirror)
			)
		)
		(fp_text user "License: Apache-2.0"
			(at -0.939 -5.799 90)
			(layer "B.Fab")
			(effects
				(font
					(size 0.7 0.7)
					(thickness 0.15)
				)
				(justify left bottom mirror)
			)
		)
		(fp_text user "${REFERENCE}"
			(at -0.939 -4.599 90)
			(layer "B.Fab")
			(effects
				(font
					(size 0.7 0.7)
					(thickness 0.15)
				)
				(justify left bottom mirror)
			)
		)
		(pad "1" smd roundrect
			(at -0.48 0 270)
			(size 0.59 0.64)
			(layers "B.Cu" "B.Mask" "B.Paste")
			(roundrect_rratio 0.25)
			(net 733 "/Expansion connector/DP1.TX2-")
			(pintype "passive")
		)
		(pad "2" smd roundrect
			(at 0.48 0 270)
			(size 0.59 0.64)
			(layers "B.Cu" "B.Mask" "B.Paste")
			(roundrect_rratio 0.25)
			(net 1250 "/SoM_IO2/DP1.TX2_C-")
			(pintype "passive")
		)
	)
	(footprint "antmicro-footprints:R_0402_1005Metric"
		(layer "B.Cu")
		(at 235.694 107.8)
		(descr "Resistor SMD 0402")
		(tags "resistor SMD 0402")
		(property "Reference" "R269"
			(at -2.894 3.7 0)
			(layer "B.SilkS")
			(effects
				(font
					(size 0.7 0.7)
					(thickness 0.15)
				)
				(justify right top mirror)
			)
		)
		(property "Value" "R_10k_0402"
			(at -1.011843 -1.772046 0)
			(layer "B.Fab")
			(effects
				(font
					(size 0.7 0.7)
					(thickness 0.15)
				)
				(justify right top mirror)
			)
		)
		(property "Datasheet" "https://www.bourns.com/docs/product-datasheets/cr.pdf"
			(at 0 0 0)
			(layer "B.Fab")
			(hide yes)
			(effects
				(font
					(size 1.27 1.27)
					(thickness 0.15)
				)
				(justify mirror)
			)
		)
		(property "Description" "SMD Chip Resistor, 10 kohm, ± 1%, 62.5 mW, 0402 [1005 Metric], Thick Film, General Purpose"
			(at 0 0 0)
			(layer "B.Fab")
			(hide yes)
			(effects
				(font
					(size 1.27 1.27)
					(thickness 0.15)
				)
				(justify mirror)
			)
		)
		(property "Manufacturer" "Bourns"
			(at 0 0 180)
			(unlocked yes)
			(layer "B.Fab")
			(hide yes)
			(effects
				(font
					(size 1 1)
					(thickness 0.15)
				)
				(justify mirror)
			)
		)
		(property "MPN" "CR0402-FX-1002GLF"
			(at 0 0 180)
			(unlocked yes)
			(layer "B.Fab")
			(hide yes)
			(effects
				(font
					(size 1 1)
					(thickness 0.15)
				)
				(justify mirror)
			)
		)
		(property "Val" "10k"
			(at 0 0 180)
			(unlocked yes)
			(layer "B.Fab")
			(hide yes)
			(effects
				(font
					(size 1 1)
					(thickness 0.15)
				)
				(justify mirror)
			)
		)
		(property "License" "Apache-2.0"
			(at 0 0 180)
			(unlocked yes)
			(layer "B.Fab")
			(hide yes)
			(effects
				(font
					(size 1 1)
					(thickness 0.15)
				)
				(justify mirror)
			)
		)
		(property "Author" "Antmicro"
			(at 0 0 180)
			(unlocked yes)
			(layer "B.Fab")
			(hide yes)
			(effects
				(font
					(size 1 1)
					(thickness 0.15)
				)
				(justify mirror)
			)
		)
		(property "Tolerance" "1%"
			(at 0 0 180)
			(unlocked yes)
			(layer "B.Fab")
			(hide yes)
			(effects
				(font
					(size 1 1)
					(thickness 0.15)
				)
				(justify mirror)
			)
		)
		(sheetname "/Recovery USB/")
		(sheetfile "recovery_usb.kicad_sch")
		(attr smd)
		(fp_poly
			(pts
				(xy -0.925 0.47) (xy -0.925 -0.47) (xy 0.925 -0.47) (xy 0.925 0.47)
			)
			(stroke
				(width 0.05)
				(type default)
			)
			(fill no)
			(layer "B.CrtYd")
		)
		(fp_poly
			(pts
				(xy -0.5 0.25) (xy -0.5 -0.25) (xy 0.5 -0.25) (xy 0.5 0.25)
			)
			(stroke
				(width 0.15)
				(type solid)
			)
			(fill no)
			(layer "B.Fab")
		)
		(fp_text user "Author: Antmicro"
			(at -0.95 -4.169 0)
			(layer "B.Fab")
			(effects
				(font
					(size 0.7 0.7)
					(thickness 0.15)
				)
				(justify right top mirror)
			)
		)
		(fp_text user "License: Apache-2.0"
			(at -0.949999 -5.169 0)
			(layer "B.Fab")
			(effects
				(font
					(size 0.7 0.7)
					(thickness 0.15)
				)
				(justify right top mirror)
			)
		)
		(fp_text user "${REFERENCE}"
			(at -0.95 -3.168 0)
			(layer "B.Fab")
			(effects
				(font
					(size 0.7 0.7)
					(thickness 0.15)
				)
				(justify right top mirror)
			)
		)
		(pad "1" smd roundrect
			(at -0.48 0)
			(size 0.59 0.64)
			(layers "B.Cu" "B.Mask" "B.Paste")
			(roundrect_rratio 0.25)
			(net 890 "Net-(Q19-D)")
			(pintype "passive")
		)
		(pad "2" smd roundrect
			(at 0.48 0)
			(size 0.59 0.64)
			(layers "B.Cu" "B.Mask" "B.Paste")
			(roundrect_rratio 0.25)
			(net 1245 "Net-(R265-Pad1)")
			(pintype "passive")
		)
	)
	(footprint "antmicro-footprints:R_0402_1005Metric"
		(layer "B.Cu")
		(at 207.8 82.3 180)
		(descr "Resistor SMD 0402")
		(tags "resistor SMD 0402")
		(property "Reference" "R97"
			(at -3.14 0.6 0)
			(layer "B.SilkS")
			(effects
				(font
					(size 0.7 0.7)
					(thickness 0.15)
				)
				(justify left bottom mirror)
			)
		)
		(property "Value" "R_100k_0402"
			(at -1.011843 -1.772046 0)
			(layer "B.Fab")
			(effects
				(font
					(size 0.7 0.7)
					(thickness 0.15)
				)
				(justify left bottom mirror)
			)
		)
		(property "Datasheet" "https://www.bourns.com/docs/product-datasheets/cr.pdf"
			(at 0 0 0)
			(layer "B.Fab")
			(hide yes)
			(effects
				(font
					(size 1.27 1.27)
					(thickness 0.15)
				)
				(justify mirror)
			)
		)
		(property "Description" "SMD Chip Resistor, 100 kohm, ± 1%, 62.5 mW, 0402 [1005 Metric], Thick Film, General Purpose"
			(at 0 0 0)
			(layer "B.Fab")
			(hide yes)
			(effects
				(font
					(size 1.27 1.27)
					(thickness 0.15)
				)
				(justify mirror)
			)
		)
		(property "Manufacturer" "Bourns"
			(at 0 0 0)
			(unlocked yes)
			(layer "B.Fab")
			(hide yes)
			(effects
				(font
					(size 1 1)
					(thickness 0.15)
				)
				(justify mirror)
			)
		)
		(property "MPN" "CR0402-FX-1003GLF"
			(at 0 0 0)
			(unlocked yes)
			(layer "B.Fab")
			(hide yes)
			(effects
				(font
					(size 1 1)
					(thickness 0.15)
				)
				(justify mirror)
			)
		)
		(property "Val" "100k"
			(at 0 0 0)
			(unlocked yes)
			(layer "B.Fab")
			(hide yes)
			(effects
				(font
					(size 1 1)
					(thickness 0.15)
				)
				(justify mirror)
			)
		)
		(property "License" "Apache-2.0"
			(at 0 0 0)
			(unlocked yes)
			(layer "B.Fab")
			(hide yes)
			(effects
				(font
					(size 1 1)
					(thickness 0.15)
				)
				(justify mirror)
			)
		)
		(property "Author" "Antmicro"
			(at 0 0 0)
			(unlocked yes)
			(layer "B.Fab")
			(hide yes)
			(effects
				(font
					(size 1 1)
					(thickness 0.15)
				)
				(justify mirror)
			)
		)
		(property "Tolerance" "1%"
			(at 0 0 0)
			(unlocked yes)
			(layer "B.Fab")
			(hide yes)
			(effects
				(font
					(size 1 1)
					(thickness 0.15)
				)
				(justify mirror)
			)
		)
		(sheetname "/USB Debug, PD/")
		(sheetfile "usb_debug_pd.kicad_sch")
		(attr smd)
		(fp_poly
			(pts
				(xy -0.925 0.47) (xy 0.925 0.47) (xy 0.925 -0.47) (xy -0.925 -0.47)
			)
			(stroke
				(width 0.05)
				(type default)
			)
			(fill no)
			(layer "B.CrtYd")
		)
		(fp_poly
			(pts
				(xy -0.5 0.25) (xy 0.5 0.25) (xy 0.5 -0.25) (xy -0.5 -0.25)
			)
			(stroke
				(width 0.15)
				(type solid)
			)
			(fill no)
			(layer "B.Fab")
		)
		(fp_text user "${REFERENCE}"
			(at -0.95 -3.168 0)
			(layer "B.Fab")
			(effects
				(font
					(size 0.7 0.7)
					(thickness 0.15)
				)
				(justify left bottom mirror)
			)
		)
		(fp_text user "Author: Antmicro"
			(at -0.95 -4.169 0)
			(layer "B.Fab")
			(effects
				(font
					(size 0.7 0.7)
					(thickness 0.15)
				)
				(justify left bottom mirror)
			)
		)
		(fp_text user "License: Apache-2.0"
			(at -0.949999 -5.169 0)
			(layer "B.Fab")
			(effects
				(font
					(size 0.7 0.7)
					(thickness 0.15)
				)
				(justify left bottom mirror)
			)
		)
		(pad "1" smd roundrect
			(at -0.48 0 180)
			(size 0.59 0.64)
			(layers "B.Cu" "B.Mask" "B.Paste")
			(roundrect_rratio 0.25)
			(net 1 "GND")
			(pintype "passive")
		)
		(pad "2" smd roundrect
			(at 0.48 0 180)
			(size 0.59 0.64)
			(layers "B.Cu" "B.Mask" "B.Paste")
			(roundrect_rratio 0.25)
			(net 935 "/USB Debug, PD/PDC_ADCIN2")
			(pintype "passive")
		)
	)
	(footprint "antmicro-footprints:TP_SMD_0.75mm"
		(layer "B.Cu")
		(at 232.3 79.6 -90)
		(property "Reference" "TP19"
			(at 1.1 0.3 0)
			(layer "B.SilkS")
			(effects
				(font
					(size 0.7 0.7)
					(thickness 0.15)
				)
				(justify left bottom mirror)
			)
		)
		(property "Value" "TP_0.75mm_SMD"
			(at 0 -1.2 90)
			(layer "B.Fab")
			(effects
				(font
					(size 0.7 0.7)
					(thickness 0.15)
				)
				(justify left bottom mirror)
			)
		)
		(property "Description" "SMT test point"
			(at 0 0 90)
			(layer "B.Fab")
			(hide yes)
			(effects
				(font
					(size 1.27 1.27)
					(thickness 0.15)
				)
				(justify mirror)
			)
		)
		(property "MPN" ""
			(at 0 0 90)
			(unlocked yes)
			(layer "B.Fab")
			(hide yes)
			(effects
				(font
					(size 1 1)
					(thickness 0.15)
				)
				(justify mirror)
			)
		)
		(property "Manufacturer" ""
			(at 0 0 90)
			(unlocked yes)
			(layer "B.Fab")
			(hide yes)
			(effects
				(font
					(size 1 1)
					(thickness 0.15)
				)
				(justify mirror)
			)
		)
		(property "Author" "Antmicro"
			(at 0 0 90)
			(unlocked yes)
			(layer "B.Fab")
			(hide yes)
			(effects
				(font
					(size 1 1)
					(thickness 0.15)
				)
				(justify mirror)
			)
		)
		(property "License" "Apache-2.0"
			(at 0 0 90)
			(unlocked yes)
			(layer "B.Fab")
			(hide yes)
			(effects
				(font
					(size 1 1)
					(thickness 0.15)
				)
				(justify mirror)
			)
		)
		(sheetname "/USB Debug, PD/")
		(sheetfile "usb_debug_pd.kicad_sch")
		(attr exclude_from_pos_files exclude_from_bom)
		(fp_circle
			(center 0 0)
			(end 0.475 0)
			(stroke
				(width 0.05)
				(type default)
			)
			(fill no)
			(layer "B.CrtYd")
		)
		(fp_text user "License: Apache-2.0"
			(at -0.4 -5.101 90)
			(layer "B.Fab")
			(effects
				(font
					(size 0.7 0.7)
					(thickness 0.15)
				)
				(justify left bottom mirror)
			)
		)
		(fp_text user "Author: Antmicro"
			(at -0.4 -3.901 90)
			(layer "B.Fab")
			(effects
				(font
					(size 0.7 0.7)
					(thickness 0.15)
				)
				(justify left bottom mirror)
			)
		)
		(fp_text user "${REFERENCE}"
			(at -0.4 -2.7 90)
			(layer "B.Fab")
			(effects
				(font
					(size 0.7 0.7)
					(thickness 0.15)
				)
				(justify left bottom mirror)
			)
		)
		(pad "1" smd circle
			(at 0 0 270)
			(size 0.75 0.75)
			(layers "B.Cu" "B.Mask")
			(net 976 "/USB Debug, PD/USBC0_FLG")
			(pinfunction "1")
			(pintype "passive")
		)
	)
)
